(kicad_pcb
	(version 20260206)
	(generator "pcbnew")
	(generator_version "10.0")
	(general
		(thickness 1.6)
		(legacy_teardrops no)
	)
	(paper "A4")
	(title_block
		(title "timecard-production-celestica-r4006 — R4006-B0001-02_R01.brd")
		(comment 1 "Time Appliance Project (Time Card) / footprints 920-924 of 1113")
	)
	(layers
		(0 "F.Cu" signal "TOP")
		(4 "In1.Cu" signal "L02_GND1")
		(6 "In2.Cu" signal "L03_SIG1")
		(8 "In3.Cu" signal "L04_GND2")
		(10 "In4.Cu" signal "L05_VCC1")
		(12 "In5.Cu" signal "L06_VCC2")
		(14 "In6.Cu" signal "L07_GND3")
		(16 "In7.Cu" signal "L08_SIG2")
		(18 "In8.Cu" signal "L09_GND4")
		(2 "B.Cu" signal "BOTTOM")
		(9 "F.Adhes" user "F.Adhesive")
		(11 "B.Adhes" user "B.Adhesive")
		(13 "F.Paste" user "Package Geometry/Pastemask Top")
		(15 "B.Paste" user "Package Geometry/Pastemask Bottom")
		(5 "F.SilkS" user "Ref Des/Silkscreen Top")
		(7 "B.SilkS" user "Ref Des/Silkscreen Bottom")
		(1 "F.Mask" user "Board Geometry/Soldermask Top")
		(3 "B.Mask" user "Board Geometry/Soldermask Bottom")
		(17 "Dwgs.User" user "User.Drawings")
		(19 "Cmts.User" user "User.Comments")
		(21 "Eco1.User" user "User.Eco1")
		(23 "Eco2.User" user "User.Eco2")
		(25 "Edge.Cuts" user "Board Geometry/Outline")
		(27 "Margin" user)
		(31 "F.CrtYd" user "Package Geometry/Place Bound Top")
		(29 "B.CrtYd" user "Package Geometry/Place Bound Bottom")
		(35 "F.Fab" user "Ref Des/Assembly Top")
		(33 "B.Fab" user "Ref Des/Assembly Bottom")
	)
	(footprint ""
		(layer "B.Cu")
		(at 83.2358 -81.407 180)
		(property "Reference" "R149"
			(at 0.1778 -2.19837 0)
			(unlocked yes)
			(layer "B.SilkS")
			(effects
				(font
					(size 0.7874 0.5842)
					(thickness 0.1524)
				)
				(justify mirror)
			)
		)
		(property "Value" "VAL*"
			(at -0.02032 2.13233 180)
			(unlocked yes)
			(layer "B.Fab")
			(hide yes)
			(effects
				(font
					(size 0.7874 0.5842)
					(thickness 0.1524)
				)
				(justify mirror)
			)
		)
		(property "Tolerance" "TOL*"
			(at -0.044704 3.05435 180)
			(unlocked yes)
			(layer "Cmts.User")
			(hide yes)
			(effects
				(font
					(size 0.7874 0.5842)
					(thickness 0.1524)
				)
				(justify mirror)
			)
		)
		(property "User Part Number" "PARTNUM*"
			(at -0.02032 4.024884 180)
			(unlocked yes)
			(layer "Cmts.User")
			(hide yes)
			(effects
				(font
					(size 0.7874 0.5842)
					(thickness 0.1524)
				)
				(justify mirror)
			)
		)
		(property "Device Type" "RESISTOR-G155-14701-01,4.7KOHMA"
			(at -0.008382 1.210564 180)
			(unlocked yes)
			(layer "B.Fab")
			(hide yes)
			(effects
				(font
					(size 0.7874 0.5842)
					(thickness 0.1524)
				)
				(justify mirror)
			)
		)
		(duplicate_pad_numbers_are_jumpers no)
		(fp_line
			(start 1.143 0.5588)
			(end -1.143 0.5588)
			(stroke
				(width 0.1)
				(type default)
			)
			(layer "B.SilkS")
		)
		(fp_line
			(start 1.143 -0.5588)
			(end 1.143 0.5588)
			(stroke
				(width 0.1)
				(type default)
			)
			(layer "B.SilkS")
		)
		(fp_line
			(start -1.143 0.5588)
			(end -1.143 -0.5588)
			(stroke
				(width 0.1)
				(type default)
			)
			(layer "B.SilkS")
		)
		(fp_line
			(start -1.143 -0.5588)
			(end 1.143 -0.5588)
			(stroke
				(width 0.1)
				(type default)
			)
			(layer "B.SilkS")
		)
		(fp_rect
			(start -1.143 0.5588)
			(end 1.143 -0.5588)
			(stroke
				(width 0)
				(type default)
			)
			(fill no)
			(layer "B.CrtYd")
		)
		(fp_line
			(start 0.508 0.3048)
			(end -0.508 0.3048)
			(stroke
				(width 0.1)
				(type default)
			)
			(layer "B.Fab")
		)
		(fp_line
			(start 0.508 -0.3048)
			(end 0.508 0.3048)
			(stroke
				(width 0.1)
				(type default)
			)
			(layer "B.Fab")
		)
		(fp_line
			(start -0.508 0.3048)
			(end -0.508 -0.3048)
			(stroke
				(width 0.1)
				(type default)
			)
			(layer "B.Fab")
		)
		(fp_line
			(start -0.508 -0.3048)
			(end 0.508 -0.3048)
			(stroke
				(width 0.1)
				(type default)
			)
			(layer "B.Fab")
		)
		(pad "1" smd rect
			(at 0.5334 0)
			(size 0.7112 0.6096)
			(layers "B.Cu" "B.Mask" "B.Paste")
			(net "XP3R3V_FPGA")
		)
		(pad "2" smd rect
			(at -0.5334 0)
			(size 0.7112 0.6096)
			(layers "B.Cu" "B.Mask" "B.Paste")
			(net "UNNAMED_5_PCA9546APWTSSOP16_I33")
		)
		(zone
			(layer "B.Cu")
			(hatch none 0.5)
			(connect_pads
				(clearance 0)
			)
			(min_thickness 0.25)
			(keepout
				(tracks allowed)
				(vias not_allowed)
				(pads allowed)
				(copperpour not_allowed)
				(footprints allowed)
			)
			(placement
				(enabled no)
				(sheetname "")
			)
			(fill
				(thermal_gap 0.5)
				(thermal_bridge_width 0.5)
				(island_removal_mode 0)
			)
			(polygon
				(pts
					(xy 83.312 -81.7118) (xy 83.1596 -81.7118) (xy 83.1596 -81.1022) (xy 83.312 -81.1022)
				)
			)
		)
	)
	(footprint ""
		(layer "B.Cu")
		(at 116.459 -29.464 90)
		(property "Reference" "R441"
			(at -3.429 -0.03937 270)
			(unlocked yes)
			(layer "B.SilkS")
			(effects
				(font
					(size 0.7874 0.5842)
					(thickness 0.1524)
				)
				(justify mirror)
			)
		)
		(property "Value" "VAL*"
			(at -0.02032 2.13233 90)
			(unlocked yes)
			(layer "B.Fab")
			(hide yes)
			(effects
				(font
					(size 0.7874 0.5842)
					(thickness 0.1524)
				)
				(justify mirror)
			)
		)
		(property "Tolerance" "TOL*"
			(at -0.044704 3.05435 90)
			(unlocked yes)
			(layer "Cmts.User")
			(hide yes)
			(effects
				(font
					(size 0.7874 0.5842)
					(thickness 0.1524)
				)
				(justify mirror)
			)
		)
		(property "User Part Number" "PARTNUM*"
			(at -0.02032 4.024884 90)
			(unlocked yes)
			(layer "Cmts.User")
			(hide yes)
			(effects
				(font
					(size 0.7874 0.5842)
					(thickness 0.1524)
				)
				(justify mirror)
			)
		)
		(property "Device Type" "RESISTOR-G155-11002-01,10KOHM,A"
			(at -0.008382 1.210564 90)
			(unlocked yes)
			(layer "B.Fab")
			(hide yes)
			(effects
				(font
					(size 0.7874 0.5842)
					(thickness 0.1524)
				)
				(justify mirror)
			)
		)
		(duplicate_pad_numbers_are_jumpers no)
		(fp_line
			(start 1.143 -0.5588)
			(end 1.143 0.5588)
			(stroke
				(width 0.1)
				(type default)
			)
			(layer "B.SilkS")
		)
		(fp_line
			(start -1.143 -0.5588)
			(end 1.143 -0.5588)
			(stroke
				(width 0.1)
				(type default)
			)
			(layer "B.SilkS")
		)
		(fp_line
			(start 1.143 0.5588)
			(end -1.143 0.5588)
			(stroke
				(width 0.1)
				(type default)
			)
			(layer "B.SilkS")
		)
		(fp_line
			(start -1.143 0.5588)
			(end -1.143 -0.5588)
			(stroke
				(width 0.1)
				(type default)
			)
			(layer "B.SilkS")
		)
		(fp_poly
			(pts
				(xy 1.143 0.5588) (xy -1.143 0.5588) (xy -1.143 -0.5588) (xy 1.143 -0.5588)
			)
			(stroke
				(width 0)
				(type default)
			)
			(fill no)
			(layer "B.CrtYd")
		)
		(fp_line
			(start 0.508 -0.3048)
			(end 0.508 0.3048)
			(stroke
				(width 0.1)
				(type default)
			)
			(layer "B.Fab")
		)
		(fp_line
			(start -0.508 -0.3048)
			(end 0.508 -0.3048)
			(stroke
				(width 0.1)
				(type default)
			)
			(layer "B.Fab")
		)
		(fp_line
			(start 0.508 0.3048)
			(end -0.508 0.3048)
			(stroke
				(width 0.1)
				(type default)
			)
			(layer "B.Fab")
		)
		(fp_line
			(start -0.508 0.3048)
			(end -0.508 -0.3048)
			(stroke
				(width 0.1)
				(type default)
			)
			(layer "B.Fab")
		)
		(pad "1" smd rect
			(at 0.5334 0 270)
			(size 0.7112 0.6096)
			(layers "B.Cu" "B.Mask" "B.Paste")
			(net "FPGA_IN_MAC_PPS_OUTN")
		)
		(pad "2" smd rect
			(at -0.5334 0 270)
			(size 0.7112 0.6096)
			(layers "B.Cu" "B.Mask" "B.Paste")
			(net "SG")
		)
		(zone
			(layer "B.Cu")
			(hatch none 0.5)
			(connect_pads
				(clearance 0)
			)
			(min_thickness 0.25)
			(keepout
				(tracks not_allowed)
				(vias allowed)
				(pads allowed)
				(copperpour not_allowed)
				(footprints allowed)
			)
			(placement
				(enabled no)
				(sheetname "")
			)
			(fill
				(thermal_gap 0.5)
				(thermal_bridge_width 0.5)
				(island_removal_mode 0)
			)
			(polygon
				(pts
					(xy 116.7638 -29.5402) (xy 116.1542 -29.5402) (xy 116.1542 -29.3878) (xy 116.7638 -29.3878)
				)
			)
		)
		(zone
			(layer "B.Cu")
			(hatch none 0.5)
			(connect_pads
				(clearance 0)
			)
			(min_thickness 0.25)
			(keepout
				(tracks allowed)
				(vias not_allowed)
				(pads allowed)
				(copperpour not_allowed)
				(footprints allowed)
			)
			(placement
				(enabled no)
				(sheetname "")
			)
			(fill
				(thermal_gap 0.5)
				(thermal_bridge_width 0.5)
				(island_removal_mode 0)
			)
			(polygon
				(pts
					(xy 116.7638 -29.5402) (xy 116.1542 -29.5402) (xy 116.1542 -29.3878) (xy 116.7638 -29.3878)
				)
			)
		)
	)
	(footprint ""
		(layer "B.Cu")
		(at 111.125 -103.251)
		(property "Reference" "R321"
			(at 0.381 -3.26263 0)
			(unlocked yes)
			(layer "B.SilkS")
			(effects
				(font
					(size 0.7874 0.5842)
					(thickness 0.1524)
				)
				(justify mirror)
			)
		)
		(property "Value" "VAL*"
			(at -0.02032 2.13233 0)
			(unlocked yes)
			(layer "B.Fab")
			(hide yes)
			(effects
				(font
					(size 0.7874 0.5842)
					(thickness 0.1524)
				)
				(justify mirror)
			)
		)
		(property "Tolerance" "TOL*"
			(at -0.044704 3.05435 0)
			(unlocked yes)
			(layer "Cmts.User")
			(hide yes)
			(effects
				(font
					(size 0.7874 0.5842)
					(thickness 0.1524)
				)
				(justify mirror)
			)
		)
		(property "User Part Number" "PARTNUM*"
			(at -0.02032 4.024884 0)
			(unlocked yes)
			(layer "Cmts.User")
			(hide yes)
			(effects
				(font
					(size 0.7874 0.5842)
					(thickness 0.1524)
				)
				(justify mirror)
			)
		)
		(property "Device Type" "RESISTOR-G155-133R0-01,33OHM,1%"
			(at -0.008382 1.210564 0)
			(unlocked yes)
			(layer "B.Fab")
			(hide yes)
			(effects
				(font
					(size 0.7874 0.5842)
					(thickness 0.1524)
				)
				(justify mirror)
			)
		)
		(duplicate_pad_numbers_are_jumpers no)
		(fp_line
			(start -1.143 -0.5588)
			(end 1.143 -0.5588)
			(stroke
				(width 0.1)
				(type default)
			)
			(layer "B.SilkS")
		)
		(fp_line
			(start -1.143 0.5588)
			(end -1.143 -0.5588)
			(stroke
				(width 0.1)
				(type default)
			)
			(layer "B.SilkS")
		)
		(fp_line
			(start 1.143 -0.5588)
			(end 1.143 0.5588)
			(stroke
				(width 0.1)
				(type default)
			)
			(layer "B.SilkS")
		)
		(fp_line
			(start 1.143 0.5588)
			(end -1.143 0.5588)
			(stroke
				(width 0.1)
				(type default)
			)
			(layer "B.SilkS")
		)
		(fp_poly
			(pts
				(xy 1.143 0.5588) (xy -1.143 0.5588) (xy -1.143 -0.5588) (xy 1.143 -0.5588)
			)
			(stroke
				(width 0)
				(type default)
			)
			(fill no)
			(layer "B.CrtYd")
		)
		(fp_line
			(start -0.508 -0.3048)
			(end 0.508 -0.3048)
			(stroke
				(width 0.1)
				(type default)
			)
			(layer "B.Fab")
		)
		(fp_line
			(start -0.508 0.3048)
			(end -0.508 -0.3048)
			(stroke
				(width 0.1)
				(type default)
			)
			(layer "B.Fab")
		)
		(fp_line
			(start 0.508 -0.3048)
			(end 0.508 0.3048)
			(stroke
				(width 0.1)
				(type default)
			)
			(layer "B.Fab")
		)
		(fp_line
			(start 0.508 0.3048)
			(end -0.508 0.3048)
			(stroke
				(width 0.1)
				(type default)
			)
			(layer "B.Fab")
		)
		(pad "1" smd rect
			(at 0.5334 0 180)
			(size 0.7112 0.6096)
			(layers "B.Cu" "B.Mask" "B.Paste")
			(net "FPGA_M_RGB_LED_I2C_SDA")
		)
		(pad "2" smd rect
			(at -0.5334 0 180)
			(size 0.7112 0.6096)
			(layers "B.Cu" "B.Mask" "B.Paste")
			(net "R_RGB_LED_I2C_SDA")
		)
		(zone
			(layer "B.Cu")
			(hatch none 0.5)
			(connect_pads
				(clearance 0)
			)
			(min_thickness 0.25)
			(keepout
				(tracks not_allowed)
				(vias allowed)
				(pads allowed)
				(copperpour not_allowed)
				(footprints allowed)
			)
			(placement
				(enabled no)
				(sheetname "")
			)
			(fill
				(thermal_gap 0.5)
				(thermal_bridge_width 0.5)
				(island_removal_mode 0)
			)
			(polygon
				(pts
					(xy 111.2012 -102.9462) (xy 111.2012 -103.5558) (xy 111.0488 -103.5558) (xy 111.0488 -102.9462)
				)
			)
		)
		(zone
			(layer "B.Cu")
			(hatch none 0.5)
			(connect_pads
				(clearance 0)
			)
			(min_thickness 0.25)
			(keepout
				(tracks allowed)
				(vias not_allowed)
				(pads allowed)
				(copperpour not_allowed)
				(footprints allowed)
			)
			(placement
				(enabled no)
				(sheetname "")
			)
			(fill
				(thermal_gap 0.5)
				(thermal_bridge_width 0.5)
				(island_removal_mode 0)
			)
			(polygon
				(pts
					(xy 111.2012 -102.9462) (xy 111.2012 -103.5558) (xy 111.0488 -103.5558) (xy 111.0488 -102.9462)
				)
			)
		)
	)
	(footprint ""
		(layer "B.Cu")
		(at 26.8986 -18.2372)
		(property "Reference" "R344"
			(at -0.2286 1.38557 0)
			(unlocked yes)
			(layer "B.SilkS")
			(effects
				(font
					(size 0.7874 0.5842)
					(thickness 0.1524)
				)
				(justify mirror)
			)
		)
		(property "Value" "VAL*"
			(at -0.02032 2.13233 0)
			(unlocked yes)
			(layer "B.Fab")
			(hide yes)
			(effects
				(font
					(size 0.7874 0.5842)
					(thickness 0.1524)
				)
				(justify mirror)
			)
		)
		(property "Tolerance" "TOL*"
			(at -0.044704 3.05435 0)
			(unlocked yes)
			(layer "Cmts.User")
			(hide yes)
			(effects
				(font
					(size 0.7874 0.5842)
					(thickness 0.1524)
				)
				(justify mirror)
			)
		)
		(property "User Part Number" "PARTNUM*"
			(at -0.02032 4.024884 0)
			(unlocked yes)
			(layer "Cmts.User")
			(hide yes)
			(effects
				(font
					(size 0.7874 0.5842)
					(thickness 0.1524)
				)
				(justify mirror)
			)
		)
		(property "Device Type" "RESISTOR-G155-14701-01,4.7KOHMA"
			(at -0.008382 1.210564 0)
			(unlocked yes)
			(layer "B.Fab")
			(hide yes)
			(effects
				(font
					(size 0.7874 0.5842)
					(thickness 0.1524)
				)
				(justify mirror)
			)
		)
		(duplicate_pad_numbers_are_jumpers no)
		(fp_line
			(start -1.143 -0.5588)
			(end 1.143 -0.5588)
			(stroke
				(width 0.1)
				(type default)
			)
			(layer "B.SilkS")
		)
		(fp_line
			(start -1.143 0.5588)
			(end -1.143 -0.5588)
			(stroke
				(width 0.1)
				(type default)
			)
			(layer "B.SilkS")
		)
		(fp_line
			(start 1.143 -0.5588)
			(end 1.143 0.5588)
			(stroke
				(width 0.1)
				(type default)
			)
			(layer "B.SilkS")
		)
		(fp_line
			(start 1.143 0.5588)
			(end -1.143 0.5588)
			(stroke
				(width 0.1)
				(type default)
			)
			(layer "B.SilkS")
		)
		(fp_rect
			(start 1.143 -0.5588)
			(end -1.143 0.5588)
			(stroke
				(width 0)
				(type default)
			)
			(fill no)
			(layer "B.CrtYd")
		)
		(fp_line
			(start -0.508 -0.3048)
			(end 0.508 -0.3048)
			(stroke
				(width 0.1)
				(type default)
			)
			(layer "B.Fab")
		)
		(fp_line
			(start -0.508 0.3048)
			(end -0.508 -0.3048)
			(stroke
				(width 0.1)
				(type default)
			)
			(layer "B.Fab")
		)
		(fp_line
			(start 0.508 -0.3048)
			(end 0.508 0.3048)
			(stroke
				(width 0.1)
				(type default)
			)
			(layer "B.Fab")
		)
		(fp_line
			(start 0.508 0.3048)
			(end -0.508 0.3048)
			(stroke
				(width 0.1)
				(type default)
			)
			(layer "B.Fab")
		)
		(pad "1" smd rect
			(at 0.5334 0 180)
			(size 0.7112 0.6096)
			(layers "B.Cu" "B.Mask" "B.Paste")
			(net "SN_EEPROM_WP")
		)
		(pad "2" smd rect
			(at -0.5334 0 180)
			(size 0.7112 0.6096)
			(layers "B.Cu" "B.Mask" "B.Paste")
			(net "SG")
		)
		(zone
			(layer "B.Cu")
			(hatch none 0.5)
			(connect_pads
				(clearance 0)
			)
			(min_thickness 0.25)
			(keepout
				(tracks allowed)
				(vias not_allowed)
				(pads allowed)
				(copperpour not_allowed)
				(footprints allowed)
			)
			(placement
				(enabled no)
				(sheetname "")
			)
			(fill
				(thermal_gap 0.5)
				(thermal_bridge_width 0.5)
				(island_removal_mode 0)
			)
			(polygon
				(pts
					(xy 26.9748 -18.542) (xy 26.8224 -18.542) (xy 26.8224 -17.9324) (xy 26.9748 -17.9324)
				)
			)
		)
	)
	(footprint ""
		(layer "B.Cu")
		(at 138.049 -107.696 90)
		(property "Reference" "R257"
			(at -5.88137 -0.254 0)
			(unlocked yes)
			(layer "B.SilkS")
			(effects
				(font
					(size 0.7874 0.5842)
					(thickness 0.1524)
				)
				(justify mirror)
			)
		)
		(property "Value" "VAL*"
			(at -0.02032 2.13233 90)
			(unlocked yes)
			(layer "B.Fab")
			(hide yes)
			(effects
				(font
					(size 0.7874 0.5842)
					(thickness 0.1524)
				)
				(justify mirror)
			)
		)
		(property "Device Type" "RESISTOR-G155-13300-01,330OHM,A"
			(at -0.008382 1.210564 90)
			(unlocked yes)
			(layer "B.Fab")
			(hide yes)
			(effects
				(font
					(size 0.7874 0.5842)
					(thickness 0.1524)
				)
				(justify mirror)
			)
		)
		(property "User Part Number" "PARTNUM*"
			(at -0.02032 4.024884 90)
			(unlocked yes)
			(layer "Cmts.User")
			(hide yes)
			(effects
				(font
					(size 0.7874 0.5842)
					(thickness 0.1524)
				)
				(justify mirror)
			)
		)
		(property "Tolerance" "TOL*"
			(at -0.044704 3.05435 90)
			(unlocked yes)
			(layer "Cmts.User")
			(hide yes)
			(effects
				(font
					(size 0.7874 0.5842)
					(thickness 0.1524)
				)
				(justify mirror)
			)
		)
		(duplicate_pad_numbers_are_jumpers no)
		(fp_line
			(start 1.143 -0.5588)
			(end 1.143 0.5588)
			(stroke
				(width 0.1)
				(type default)
			)
			(layer "B.SilkS")
		)
		(fp_line
			(start -1.143 -0.5588)
			(end 1.143 -0.5588)
			(stroke
				(width 0.1)
				(type default)
			)
			(layer "B.SilkS")
		)
		(fp_line
			(start 1.143 0.5588)
			(end -1.143 0.5588)
			(stroke
				(width 0.1)
				(type default)
			)
			(layer "B.SilkS")
		)
		(fp_line
			(start -1.143 0.5588)
			(end -1.143 -0.5588)
			(stroke
				(width 0.1)
				(type default)
			)
			(layer "B.SilkS")
		)
		(fp_rect
			(start -1.143 -0.5588)
			(end 1.143 0.5588)
			(stroke
				(width 0)
				(type default)
			)
			(fill no)
			(layer "B.CrtYd")
		)
		(fp_line
			(start 0.508 -0.3048)
			(end 0.508 0.3048)
			(stroke
				(width 0.1)
				(type default)
			)
			(layer "B.Fab")
		)
		(fp_line
			(start -0.508 -0.3048)
			(end 0.508 -0.3048)
			(stroke
				(width 0.1)
				(type default)
			)
			(layer "B.Fab")
		)
		(fp_line
			(start 0.508 0.3048)
			(end -0.508 0.3048)
			(stroke
				(width 0.1)
				(type default)
			)
			(layer "B.Fab")
		)
		(fp_line
			(start -0.508 0.3048)
			(end -0.508 -0.3048)
			(stroke
				(width 0.1)
				(type default)
			)
			(layer "B.Fab")
		)
		(pad "1" smd rect
			(at 0.5334 0 270)
			(size 0.7112 0.6096)
			(layers "B.Cu" "B.Mask" "B.Paste")
			(net "UNNAMED_14_OPTICAL_I12_A")
		)
		(pad "2" smd rect
			(at -0.5334 0 270)
			(size 0.7112 0.6096)
			(layers "B.Cu" "B.Mask" "B.Paste")
			(net "XP3R3V_FPGA")
		)
		(zone
			(layer "B.Cu")
			(hatch none 0.5)
			(connect_pads
				(clearance 0)
			)
			(min_thickness 0.25)
			(keepout
				(tracks allowed)
				(vias not_allowed)
				(pads allowed)
				(copperpour not_allowed)
				(footprints allowed)
			)
			(placement
				(enabled no)
				(sheetname "")
			)
			(fill
				(thermal_gap 0.5)
				(thermal_bridge_width 0.5)
				(island_removal_mode 0)
			)
			(polygon
				(pts
					(xy 137.7442 -107.6198) (xy 138.3538 -107.6198) (xy 138.3538 -107.7722) (xy 137.7442 -107.7722)
				)
			)
		)
	)
)
